(kicad_pcb
	(version 20260206)
	(generator "pcbnew")
	(generator_version "10.0")
	(general
		(thickness 1.6)
		(legacy_teardrops no)
	)
	(paper "A4")
	(title_block
		(title "03242023_DA0F0TMBIJ0_F0T_Motherboard_J_brd_V01_OCP.brd")
		(comment 1 "Grand Teton / footprints 3845-3850 of 6105")
	)
	(layers
		(0 "F.Cu" signal "TOP")
		(4 "In1.Cu" signal "GND")
		(6 "In2.Cu" signal "IN1")
		(8 "In3.Cu" signal "GND1")
		(10 "In4.Cu" signal "IN2")
		(12 "In5.Cu" signal "GND2")
		(14 "In6.Cu" signal "IN3")
		(16 "In7.Cu" signal "GND3")
		(18 "In8.Cu" signal "VCC")
		(20 "In9.Cu" signal "VCC1")
		(22 "In10.Cu" signal "GND4")
		(24 "In11.Cu" signal "IN4")
		(26 "In12.Cu" signal "GND5")
		(28 "In13.Cu" signal "IN5")
		(30 "In14.Cu" signal "GND6")
		(32 "In15.Cu" signal "IN6")
		(34 "In16.Cu" signal "GND7")
		(2 "B.Cu" signal "BOTTOM")
		(9 "F.Adhes" user "F.Adhesive")
		(11 "B.Adhes" user "B.Adhesive")
		(13 "F.Paste" user "Package Geometry/Pastemask Top")
		(15 "B.Paste" user "Package Geometry/Pastemask Bottom")
		(5 "F.SilkS" user "Ref Des/Silkscreen Top")
		(7 "B.SilkS" user "Ref Des/Silkscreen Bottom")
		(1 "F.Mask" user "Board Geometry/Soldermask Top")
		(3 "B.Mask" user "Board Geometry/Soldermask Bottom")
		(17 "Dwgs.User" user "User.Drawings")
		(19 "Cmts.User" user "User.Comments")
		(21 "Eco1.User" user "User.Eco1")
		(23 "Eco2.User" user "User.Eco2")
		(25 "Edge.Cuts" user "Board Geometry/Outline")
		(27 "Margin" user)
		(31 "F.CrtYd" user "Package Geometry/Place Bound Top")
		(29 "B.CrtYd" user "Package Geometry/Place Bound Bottom")
		(35 "F.Fab" user "Ref Des/Assembly Top")
		(33 "B.Fab" user "Ref Des/Assembly Bottom")
	)
	(footprint ""
		(layer "F.Cu")
		(at 261.704582 -71.441056 -90)
		(property "Reference" "PU73"
			(at 0.689864 -2.87274 270)
			(unlocked yes)
			(layer "F.SilkS")
			(effects
				(font
					(size 0.7874 0.5842)
					(thickness 0.1524)
				)
				(justify left)
			)
		)
		(property "Value" ""
			(at 0 0 270)
			(layer "F.Fab")
			(effects
				(font
					(size 1.27 1.27)
				)
			)
		)
		(duplicate_pad_numbers_are_jumpers no)
		(fp_line
			(start -1.549908 2.050034)
			(end -0.5842 2.050034)
			(stroke
				(width 0.1524)
				(type default)
			)
			(layer "F.SilkS")
		)
		(fp_line
			(start 0 2.050034)
			(end 1.549908 2.050034)
			(stroke
				(width 0.1524)
				(type default)
			)
			(layer "F.SilkS")
		)
		(fp_line
			(start 1.549908 2.050034)
			(end 1.549908 1.9304)
			(stroke
				(width 0.1524)
				(type default)
			)
			(layer "F.SilkS")
		)
		(fp_line
			(start -1.549908 1.9812)
			(end -1.549908 2.050034)
			(stroke
				(width 0.1524)
				(type default)
			)
			(layer "F.SilkS")
		)
		(fp_line
			(start 1.549908 -1.9812)
			(end 1.549908 -2.050034)
			(stroke
				(width 0.1524)
				(type default)
			)
			(layer "F.SilkS")
		)
		(fp_line
			(start -1.549908 -2.050034)
			(end -1.549908 -1.9812)
			(stroke
				(width 0.1524)
				(type default)
			)
			(layer "F.SilkS")
		)
		(fp_line
			(start -0.5842 -2.050034)
			(end -1.549908 -2.050034)
			(stroke
				(width 0.1524)
				(type default)
			)
			(layer "F.SilkS")
		)
		(fp_line
			(start 1.549908 -2.050034)
			(end 0.5842 -2.050034)
			(stroke
				(width 0.1524)
				(type default)
			)
			(layer "F.SilkS")
		)
		(fp_poly
			(pts
				(xy -3.273044 -2.227072) (xy -3.273044 -1.211072) (xy -2.257044 -1.719072)
			)
			(stroke
				(width 0)
				(type default)
			)
			(fill yes)
			(layer "F.SilkS")
		)
		(fp_line
			(start -1.549908 2.050034)
			(end 1.549908 2.050034)
			(stroke
				(width 0.1)
				(type default)
			)
			(layer "F.Fab")
		)
		(fp_line
			(start 1.549908 2.050034)
			(end 1.549908 -2.050034)
			(stroke
				(width 0.1)
				(type default)
			)
			(layer "F.Fab")
		)
		(fp_line
			(start -1.549908 -2.050034)
			(end -1.549908 2.050034)
			(stroke
				(width 0.1)
				(type default)
			)
			(layer "F.Fab")
		)
		(fp_line
			(start 1.549908 -2.050034)
			(end -1.549908 -2.050034)
			(stroke
				(width 0.1)
				(type default)
			)
			(layer "F.Fab")
		)
		(fp_poly
			(pts
				(xy -2.9464 -2.208022) (xy -2.9464 -1.192022) (xy -1.9304 -1.700022)
			)
			(stroke
				(width 0)
				(type default)
			)
			(fill yes)
			(layer "F.Fab")
		)
		(pad "1" smd circle
			(at -1.35001 -1.700022 270)
			(size 0 0)
			(layers "F.Cu" "F.Mask" "F.Paste")
			(net "SW_P1V05_PCH_AUX_BST")
		)
		(pad "2" smd rect
			(at -1.400048 -1.199896)
			(size 0.1778 0.8128)
			(layers "F.Cu" "F.Mask" "F.Paste")
			(net "GND")
		)
		(pad "3" smd rect
			(at -1.400048 -0.8001)
			(size 0.1778 0.8128)
			(layers "F.Cu" "F.Mask" "F.Paste")
			(net "P1V05_PCH_AUX_CS")
		)
		(pad "4" smd rect
			(at -1.400048 -0.40005)
			(size 0.1778 0.8128)
			(layers "F.Cu" "F.Mask" "F.Paste")
			(net "P1V05_PCH_AUX_MODE")
		)
		(pad "5" smd rect
			(at -1.400048 0)
			(size 0.1778 0.8128)
			(layers "F.Cu" "F.Mask" "F.Paste")
			(net "P1V05_PCH_AUX_REF")
		)
		(pad "6" smd rect
			(at -1.400048 0.40005)
			(size 0.1778 0.8128)
			(layers "F.Cu" "F.Mask" "F.Paste")
			(net "SH_P1V05_PCH_AUX_N")
		)
		(pad "7" smd rect
			(at -1.400048 0.8001)
			(size 0.1778 0.8128)
			(layers "F.Cu" "F.Mask" "F.Paste")
			(net "P1V05_PCH_AUX_FB")
		)
		(pad "8" smd rect
			(at -1.400048 1.199896)
			(size 0.1778 0.8128)
			(layers "F.Cu" "F.Mask" "F.Paste")
			(net "FM_P1V05_PCH_AUX_R_EN")
		)
		(pad "9" smd rect
			(at -1.400048 1.700022)
			(size 0.3048 0.8128)
			(layers "F.Cu" "F.Mask" "F.Paste")
			(net "PWRGD_P1V05_PCH_AUX_R")
		)
		(pad "10" smd rect
			(at -0.299974 1.299972 270)
			(size 0.3048 2.0066)
			(layers "F.Cu" "F.Mask" "F.Paste")
			(net "SW_P12V_AUX_P1V05_PCH_AUX_FLT")
		)
		(pad "11_18" smd circle
			(at 1.175004 0.275082 270)
			(size 0 0)
			(layers "F.Cu" "F.Mask" "F.Paste")
			(net "GND")
		)
		(pad "19" smd rect
			(at 1.400048 -1.700022 180)
			(size 0.3048 0.8128)
			(layers "F.Cu" "F.Mask" "F.Paste")
			(net "P1V05_PCH_AUX_VCC")
		)
		(pad "20" smd rect
			(at 0.299974 -1.299972 270)
			(size 0.3048 2.0066)
			(layers "F.Cu" "F.Mask" "F.Paste")
			(net "SW_P1V05_PCH_AUX_SW")
		)
		(pad "21" smd rect
			(at -0.299974 -1.299972 270)
			(size 0.3048 2.0066)
			(layers "F.Cu" "F.Mask" "F.Paste")
			(net "SW_P12V_AUX_P1V05_PCH_AUX_FLT")
		)
	)
	(footprint ""
		(layer "F.Cu")
		(at 343.73439 -70.52056 90)
		(property "Reference" "C152"
			(at 0 0 90)
			(layer "F.SilkS")
			(hide yes)
			(effects
				(font
					(size 1.27 1.27)
				)
			)
		)
		(property "Value" ""
			(at 0 0 90)
			(layer "F.Fab")
			(effects
				(font
					(size 1.27 1.27)
				)
			)
		)
		(duplicate_pad_numbers_are_jumpers no)
		(fp_line
			(start 0.299974 -0.150114)
			(end 0.299974 0.150114)
			(stroke
				(width 0.1)
				(type default)
			)
			(layer "F.Fab")
		)
		(fp_line
			(start -0.299974 -0.150114)
			(end 0.299974 -0.150114)
			(stroke
				(width 0.1)
				(type default)
			)
			(layer "F.Fab")
		)
		(fp_line
			(start 0.299974 0.150114)
			(end -0.299974 0.150114)
			(stroke
				(width 0.1)
				(type default)
			)
			(layer "F.Fab")
		)
		(fp_line
			(start -0.299974 0.150114)
			(end -0.299974 -0.150114)
			(stroke
				(width 0.1)
				(type default)
			)
			(layer "F.Fab")
		)
		(pad "1" smd rect
			(at -0.2667 0 90)
			(size 0.3048 0.381)
			(layers "F.Cu" "F.Mask" "F.Paste")
			(net "DMI_CPU0_PCH_TX_C_DP<1>")
		)
		(pad "2" smd rect
			(at 0.2667 0 90)
			(size 0.3048 0.381)
			(layers "F.Cu" "F.Mask" "F.Paste")
			(net "DMI_CPU0_PCH_TX_DP<1>")
		)
	)
	(footprint ""
		(layer "F.Cu")
		(at 465.089748 -62.166246 90)
		(property "Reference" "PL45"
			(at -0.437388 -6.243828 0)
			(unlocked yes)
			(layer "F.SilkS")
			(effects
				(font
					(size 0.7874 0.5842)
					(thickness 0.1524)
				)
				(justify left)
			)
		)
		(property "Value" ""
			(at 0 0 90)
			(layer "F.Fab")
			(effects
				(font
					(size 1.27 1.27)
				)
			)
		)
		(duplicate_pad_numbers_are_jumpers no)
		(fp_line
			(start 2.249932 -2.249932)
			(end 2.249932 -1.3843)
			(stroke
				(width 0.1524)
				(type default)
			)
			(layer "F.SilkS")
		)
		(fp_line
			(start -2.249932 -2.249932)
			(end 2.249932 -2.249932)
			(stroke
				(width 0.1524)
				(type default)
			)
			(layer "F.SilkS")
		)
		(fp_line
			(start -2.249932 -1.3843)
			(end -2.249932 -2.249932)
			(stroke
				(width 0.1524)
				(type default)
			)
			(layer "F.SilkS")
		)
		(fp_line
			(start 2.249932 1.3843)
			(end 2.249932 2.249932)
			(stroke
				(width 0.1524)
				(type default)
			)
			(layer "F.SilkS")
		)
		(fp_line
			(start 2.249932 2.249932)
			(end -2.249932 2.249932)
			(stroke
				(width 0.1524)
				(type default)
			)
			(layer "F.SilkS")
		)
		(fp_line
			(start -2.249932 2.249932)
			(end -2.249932 1.3843)
			(stroke
				(width 0.1524)
				(type default)
			)
			(layer "F.SilkS")
		)
		(fp_line
			(start 2.249932 -2.249932)
			(end 2.249932 2.249932)
			(stroke
				(width 0.1)
				(type default)
			)
			(layer "F.Fab")
		)
		(fp_line
			(start -2.249932 -2.249932)
			(end 2.249932 -2.249932)
			(stroke
				(width 0.1)
				(type default)
			)
			(layer "F.Fab")
		)
		(fp_line
			(start 2.249932 2.249932)
			(end -2.249932 2.249932)
			(stroke
				(width 0.1)
				(type default)
			)
			(layer "F.Fab")
		)
		(fp_line
			(start -2.249932 2.249932)
			(end -2.249932 -2.249932)
			(stroke
				(width 0.1)
				(type default)
			)
			(layer "F.Fab")
		)
		(pad "1" smd rect
			(at -1.82499 0 90)
			(size 1.0668 2.5146)
			(layers "F.Cu" "F.Mask" "F.Paste")
			(net "P12V_AUX")
		)
		(pad "2" smd rect
			(at 1.82499 0 90)
			(size 1.0668 2.5146)
			(layers "F.Cu" "F.Mask" "F.Paste")
			(net "SW_P3V3_AUX_FLT")
		)
	)
	(footprint ""
		(layer "F.Cu")
		(at 94.20606 -414.218628 90)
		(property "Reference" "Q148"
			(at -2.023872 -0.03556 0)
			(unlocked yes)
			(layer "F.SilkS")
			(effects
				(font
					(size 0.7874 0.5842)
					(thickness 0.1524)
				)
				(justify left)
			)
		)
		(property "Value" ""
			(at 0 0 90)
			(layer "F.Fab")
			(effects
				(font
					(size 1.27 1.27)
				)
			)
		)
		(duplicate_pad_numbers_are_jumpers no)
		(fp_line
			(start 1.332738 -1.100074)
			(end 1.332738 1.100074)
			(stroke
				(width 0.1524)
				(type default)
			)
			(layer "F.SilkS")
		)
		(fp_line
			(start 0.4826 -1.100074)
			(end 1.332738 -1.100074)
			(stroke
				(width 0.1524)
				(type default)
			)
			(layer "F.SilkS")
		)
		(fp_line
			(start -0.4826 -1.100074)
			(end 0 -0.541274)
			(stroke
				(width 0.1524)
				(type default)
			)
			(layer "F.SilkS")
		)
		(fp_line
			(start -1.332738 -1.100074)
			(end -0.4826 -1.100074)
			(stroke
				(width 0.1524)
				(type default)
			)
			(layer "F.SilkS")
		)
		(fp_line
			(start 0 -0.541274)
			(end 0.4826 -1.100074)
			(stroke
				(width 0.1524)
				(type default)
			)
			(layer "F.SilkS")
		)
		(fp_line
			(start 1.332738 1.100074)
			(end -1.332738 1.100074)
			(stroke
				(width 0.1524)
				(type default)
			)
			(layer "F.SilkS")
		)
		(fp_line
			(start -1.332738 1.100074)
			(end -1.332738 -1.100074)
			(stroke
				(width 0.1524)
				(type default)
			)
			(layer "F.SilkS")
		)
		(fp_poly
			(pts
				(xy -2.27838 -1.082294) (xy -1.576324 -0.731266) (xy -2.27838 -0.380238)
			)
			(stroke
				(width 0)
				(type default)
			)
			(fill yes)
			(layer "F.SilkS")
		)
		(fp_line
			(start 0.674878 -1.100074)
			(end 0.674878 1.100074)
			(stroke
				(width 0.1)
				(type default)
			)
			(layer "F.Fab")
		)
		(fp_line
			(start -0.674878 -1.100074)
			(end 0.674878 -1.100074)
			(stroke
				(width 0.1)
				(type default)
			)
			(layer "F.Fab")
		)
		(fp_line
			(start 0.674878 1.100074)
			(end -0.674878 1.100074)
			(stroke
				(width 0.1)
				(type default)
			)
			(layer "F.Fab")
		)
		(fp_line
			(start -0.674878 1.100074)
			(end -0.674878 -1.100074)
			(stroke
				(width 0.1)
				(type default)
			)
			(layer "F.Fab")
		)
		(fp_poly
			(pts
				(xy -2.2352 -0.298958) (xy -2.2352 -1.001014) (xy -1.533144 -0.649986)
			)
			(stroke
				(width 0)
				(type default)
			)
			(fill yes)
			(layer "F.Fab")
		)
		(pad "1" smd rect
			(at -0.94996 -0.649986 180)
			(size 0.4318 0.508)
			(layers "F.Cu" "F.Mask" "F.Paste")
			(net "GND")
		)
		(pad "2" smd rect
			(at -0.94996 0 180)
			(size 0.4318 0.508)
			(layers "F.Cu" "F.Mask" "F.Paste")
			(net "HGX_DETECT_N")
		)
		(pad "3" smd rect
			(at -0.94996 0.649986 180)
			(size 0.4318 0.508)
			(layers "F.Cu" "F.Mask" "F.Paste")
			(net "HGX_DETECT_N_ISO")
		)
		(pad "4" smd rect
			(at 0.94996 0.649986 180)
			(size 0.4318 0.508)
			(layers "F.Cu" "F.Mask" "F.Paste")
			(net "GND")
		)
		(pad "5" smd rect
			(at 0.94996 0 180)
			(size 0.4318 0.508)
			(layers "F.Cu" "F.Mask" "F.Paste")
			(net "HGX_DETECT")
		)
		(pad "6" smd rect
			(at 0.94996 -0.649986 180)
			(size 0.4318 0.508)
			(layers "F.Cu" "F.Mask" "F.Paste")
			(net "HGX_DETECT")
		)
	)
	(footprint ""
		(layer "F.Cu")
		(at 313.535314 -27.078686 180)
		(property "Reference" "R1453"
			(at 0 0 180)
			(layer "F.SilkS")
			(hide yes)
			(effects
				(font
					(size 1.27 1.27)
				)
			)
		)
		(property "Value" ""
			(at 0 0 180)
			(layer "F.Fab")
			(effects
				(font
					(size 1.27 1.27)
				)
			)
		)
		(duplicate_pad_numbers_are_jumpers no)
		(fp_line
			(start 0.7874 0.4064)
			(end -0.7874 0.4064)
			(stroke
				(width 0.1524)
				(type default)
			)
			(layer "F.SilkS")
		)
		(fp_line
			(start 0.7874 -0.4064)
			(end 0.7874 0.4064)
			(stroke
				(width 0.1524)
				(type default)
			)
			(layer "F.SilkS")
		)
		(fp_line
			(start -0.7874 0.4064)
			(end -0.7874 -0.4064)
			(stroke
				(width 0.1524)
				(type default)
			)
			(layer "F.SilkS")
		)
		(fp_line
			(start -0.7874 -0.4064)
			(end 0.7874 -0.4064)
			(stroke
				(width 0.1524)
				(type default)
			)
			(layer "F.SilkS")
		)
		(fp_line
			(start 0.67945 0.3048)
			(end 0.120396 0.3048)
			(stroke
				(width 0.1)
				(type default)
			)
			(layer "F.Fab")
		)
		(fp_line
			(start 0.67945 -0.3048)
			(end 0.67945 0.3048)
			(stroke
				(width 0.1)
				(type default)
			)
			(layer "F.Fab")
		)
		(fp_line
			(start 0.12065 -0.2794)
			(end 0.12065 -0.3048)
			(stroke
				(width 0.1)
				(type default)
			)
			(layer "F.Fab")
		)
		(fp_line
			(start 0.12065 -0.3048)
			(end 0.67945 -0.3048)
			(stroke
				(width 0.1)
				(type default)
			)
			(layer "F.Fab")
		)
		(fp_line
			(start 0.120396 0.3048)
			(end 0.120396 0.2794)
			(stroke
				(width 0.1)
				(type default)
			)
			(layer "F.Fab")
		)
		(fp_line
			(start 0.120396 0.2794)
			(end -0.12065 0.2794)
			(stroke
				(width 0.1)
				(type default)
			)
			(layer "F.Fab")
		)
		(fp_line
			(start -0.12065 0.3048)
			(end -0.67945 0.3048)
			(stroke
				(width 0.1)
				(type default)
			)
			(layer "F.Fab")
		)
		(fp_line
			(start -0.12065 0.2794)
			(end -0.12065 0.3048)
			(stroke
				(width 0.1)
				(type default)
			)
			(layer "F.Fab")
		)
		(fp_line
			(start -0.12065 -0.2794)
			(end 0.12065 -0.2794)
			(stroke
				(width 0.1)
				(type default)
			)
			(layer "F.Fab")
		)
		(fp_line
			(start -0.12065 -0.305054)
			(end -0.12065 -0.2794)
			(stroke
				(width 0.1)
				(type default)
			)
			(layer "F.Fab")
		)
		(fp_line
			(start -0.67945 0.3048)
			(end -0.67945 -0.305054)
			(stroke
				(width 0.1)
				(type default)
			)
			(layer "F.Fab")
		)
		(fp_line
			(start -0.67945 -0.305054)
			(end -0.12065 -0.305054)
			(stroke
				(width 0.1)
				(type default)
			)
			(layer "F.Fab")
		)
		(pad "1" smd circle
			(at -0.40005 0 180)
			(size 0 0)
			(layers "F.Cu" "F.Mask" "F.Paste")
			(net "PU_SMB_SML4_3V3AUX_PCH_SCL")
		)
		(pad "2" smd circle
			(at 0.40005 0 180)
			(size 0 0)
			(layers "F.Cu" "F.Mask" "F.Paste")
			(net "P3V3_AUX")
		)
	)
	(footprint ""
		(layer "F.Cu")
		(at 421.54094 -101.270308 -90)
		(property "Reference" "PC2157"
			(at 0 0 270)
			(layer "F.SilkS")
			(hide yes)
			(effects
				(font
					(size 1.27 1.27)
				)
			)
		)
		(property "Value" ""
			(at 0 0 270)
			(layer "F.Fab")
			(effects
				(font
					(size 1.27 1.27)
				)
			)
		)
		(duplicate_pad_numbers_are_jumpers no)
		(fp_line
			(start -0.7874 0.4064)
			(end -0.7874 -0.4064)
			(stroke
				(width 0.1524)
				(type default)
			)
			(layer "F.SilkS")
		)
		(fp_line
			(start 0.7874 0.4064)
			(end -0.7874 0.4064)
			(stroke
				(width 0.1524)
				(type default)
			)
			(layer "F.SilkS")
		)
		(fp_line
			(start -0.7874 -0.4064)
			(end 0.7874 -0.4064)
			(stroke
				(width 0.1524)
				(type default)
			)
			(layer "F.SilkS")
		)
		(fp_line
			(start 0.7874 -0.4064)
			(end 0.7874 0.4064)
			(stroke
				(width 0.1524)
				(type default)
			)
			(layer "F.SilkS")
		)
		(fp_line
			(start -0.67945 0.3048)
			(end -0.67945 -0.305054)
			(stroke
				(width 0.1)
				(type default)
			)
			(layer "F.Fab")
		)
		(fp_line
			(start -0.12065 0.3048)
			(end -0.67945 0.3048)
			(stroke
				(width 0.1)
				(type default)
			)
			(layer "F.Fab")
		)
		(fp_line
			(start 0.120396 0.3048)
			(end 0.120396 0.2794)
			(stroke
				(width 0.1)
				(type default)
			)
			(layer "F.Fab")
		)
		(fp_line
			(start 0.67945 0.3048)
			(end 0.120396 0.3048)
			(stroke
				(width 0.1)
				(type default)
			)
			(layer "F.Fab")
		)
		(fp_line
			(start -0.12065 0.2794)
			(end -0.12065 0.3048)
			(stroke
				(width 0.1)
				(type default)
			)
			(layer "F.Fab")
		)
		(fp_line
			(start 0.120396 0.2794)
			(end -0.12065 0.2794)
			(stroke
				(width 0.1)
				(type default)
			)
			(layer "F.Fab")
		)
		(fp_line
			(start -0.12065 -0.2794)
			(end 0.12065 -0.2794)
			(stroke
				(width 0.1)
				(type default)
			)
			(layer "F.Fab")
		)
		(fp_line
			(start 0.12065 -0.2794)
			(end 0.12065 -0.3048)
			(stroke
				(width 0.1)
				(type default)
			)
			(layer "F.Fab")
		)
		(fp_line
			(start 0.12065 -0.3048)
			(end 0.67945 -0.3048)
			(stroke
				(width 0.1)
				(type default)
			)
			(layer "F.Fab")
		)
		(fp_line
			(start 0.67945 -0.3048)
			(end 0.67945 0.3048)
			(stroke
				(width 0.1)
				(type default)
			)
			(layer "F.Fab")
		)
		(fp_line
			(start -0.67945 -0.305054)
			(end -0.12065 -0.305054)
			(stroke
				(width 0.1)
				(type default)
			)
			(layer "F.Fab")
		)
		(fp_line
			(start -0.12065 -0.305054)
			(end -0.12065 -0.2794)
			(stroke
				(width 0.1)
				(type default)
			)
			(layer "F.Fab")
		)
		(pad "1" smd circle
			(at -0.40005 0 270)
			(size 0 0)
			(layers "F.Cu" "F.Mask" "F.Paste")
			(net "P3V3_OCP_MODE_1")
		)
		(pad "2" smd circle
			(at 0.40005 0 270)
			(size 0 0)
			(layers "F.Cu" "F.Mask" "F.Paste")
			(net "GND")
		)
	)
)
